1 2 3 4 5 6 12 3 4 5 6 ABCDA BCDDate: KiCad E.D.A.  kicad (5.0.1)-3Rev: Size: A4Id: 1/1 Title: File: discovery.schSheet: /12345678J1Conn_02x04_CPU+12VGND12345678J3Conn_02x04_CPU+12VGND+12V GNDPWR_FLAGPWR_FLAGW1Fixing holeGNDW2Fixing holeGNDW3Fixing holeGNDW4Fixing holeGNDW5Cable holeW6Cable holeW7Cable holeW12 Cable hole+12V+12V+12V+12VW8Cable holeW9Cable holeW10Cable holeW11Cable holeGNDGNDGNDGND123456J2Conn_02x03_PCIe+12VGND123456J4Conn_02x03_PCIe+12VGND123456J5Conn_02x03_PCIe+12VGND123456J6Conn_02x03_PCIe+12VGND